FILE_TYPE = MULTI_PHYS_TABLE;

PART '74LVC1G17GW'

{========================================================================================}
:VALUE         | PART_TYPE | MATERIAL | PART_NUMBER    = STANDARD | LIFECYCLE      | PART_NUMBER   | JEDEC_TYPE | DESCRIPTION                       | MANUFTR | MANUF_PN      | RD_CMPLS_LVL | CMPLS_LVL | FROM_PJ      | CLASS | DIP_SMD | DATA                | EE_CHECK_LIST | FP_ECN | PSL | CREATOR | STATUS | CREATEDAY  ;
{========================================================================================}
 '74LVC1G17GW' | 'SMLF'    | 'IC'     | 'AL1G0017K01'(!) = ''       | ''               | 'AL1G0017K01' |'TSSOP5'| 'IC OTHER(5P) 74LVC1G17GW(TSSOP)' | 'NXP'   | '74LVC1G17GW' | 'EP(V1)'     | 'EP(V1)'  | 'MF1-EUPHIE' | 'IC'  | ''      | 'NXP_74LVC1G17.pdf' | ''            | ''     | ''  | ''      | ''     | '20140828'
 '74LVC1G17GW' | 'SMLF'    | 'EMPTY'  | 'AL1G0017K01'(!) = ''       | ''               | 'AL1G0017K01' |'TSSOP5'| 'IC OTHER(5P) 74LVC1G17GW(TSSOP)' | 'NXP'   | '74LVC1G17GW' | 'EP(V1)'     | 'EP(V1)'  | 'MF1-EUPHIE' | 'IC'  | ''      | 'NXP_74LVC1G17.pdf' | ''            | ''     | ''  | ''      | ''     | '20140828'

END_PART

END.

